FILE_TYPE=LIBRARY_PARTS;
primitive 'CONN76_H22707001','CONN76_H22707001_THMT','CONN76_H22707001_THMT1';
  pin
    'GNDA2':
      PIN_NUMBER='(A2)';
      PINUSE='GROUND';
      NO_LOAD_CHECK='Both';
      NO_IO_CHECK='Both';
      NO_ASSERT_CHECK='TRUE';
      NO_DIR_CHECK='TRUE';
      ALLOW_CONNECT='TRUE';
    'GNDA4':
      PIN_NUMBER='(A4)';
      PINUSE='GROUND';
      NO_LOAD_CHECK='Both';
      NO_IO_CHECK='Both';
      NO_ASSERT_CHECK='TRUE';
      NO_DIR_CHECK='TRUE';
      ALLOW_CONNECT='TRUE';
    'GNDA6':
      PIN_NUMBER='(A6)';
      PINUSE='GROUND';
      NO_LOAD_CHECK='Both';
      NO_IO_CHECK='Both';
      NO_ASSERT_CHECK='TRUE';
      NO_DIR_CHECK='TRUE';
      ALLOW_CONNECT='TRUE';
    'GNDA8':
      PIN_NUMBER='(A8)';
      PINUSE='GROUND';
      NO_LOAD_CHECK='Both';
      NO_IO_CHECK='Both';
      NO_ASSERT_CHECK='TRUE';
      NO_DIR_CHECK='TRUE';
      ALLOW_CONNECT='TRUE';
    'GNDC1':
      PIN_NUMBER='(C1)';
      PINUSE='GROUND';
      NO_LOAD_CHECK='Both';
      NO_IO_CHECK='Both';
      NO_ASSERT_CHECK='TRUE';
      NO_DIR_CHECK='TRUE';
      ALLOW_CONNECT='TRUE';
    'GNDC3':
      PIN_NUMBER='(C3)';
      PINUSE='GROUND';
      NO_LOAD_CHECK='Both';
      NO_IO_CHECK='Both';
      NO_ASSERT_CHECK='TRUE';
      NO_DIR_CHECK='TRUE';
      ALLOW_CONNECT='TRUE';
    'GNDC5':
      PIN_NUMBER='(C5)';
      PINUSE='GROUND';
      NO_LOAD_CHECK='Both';
      NO_IO_CHECK='Both';
      NO_ASSERT_CHECK='TRUE';
      NO_DIR_CHECK='TRUE';
      ALLOW_CONNECT='TRUE';
    'GNDC7':
      PIN_NUMBER='(C7)';
      PINUSE='GROUND';
      NO_LOAD_CHECK='Both';
      NO_IO_CHECK='Both';
      NO_ASSERT_CHECK='TRUE';
      NO_DIR_CHECK='TRUE';
      ALLOW_CONNECT='TRUE';
    'GNDD2':
      PIN_NUMBER='(D2)';
      PINUSE='GROUND';
      NO_LOAD_CHECK='Both';
      NO_IO_CHECK='Both';
      NO_ASSERT_CHECK='TRUE';
      NO_DIR_CHECK='TRUE';
      ALLOW_CONNECT='TRUE';
    'GNDD4':
      PIN_NUMBER='(D4)';
      PINUSE='GROUND';
      NO_LOAD_CHECK='Both';
      NO_IO_CHECK='Both';
      NO_ASSERT_CHECK='TRUE';
      NO_DIR_CHECK='TRUE';
      ALLOW_CONNECT='TRUE';
    'GNDD6':
      PIN_NUMBER='(D6)';
      PINUSE='GROUND';
      NO_LOAD_CHECK='Both';
      NO_IO_CHECK='Both';
      NO_ASSERT_CHECK='TRUE';
      NO_DIR_CHECK='TRUE';
      ALLOW_CONNECT='TRUE';
    'GNDD8':
      PIN_NUMBER='(D8)';
      PINUSE='GROUND';
      NO_LOAD_CHECK='Both';
      NO_IO_CHECK='Both';
      NO_ASSERT_CHECK='TRUE';
      NO_DIR_CHECK='TRUE';
      ALLOW_CONNECT='TRUE';
    'GNDF1':
      PIN_NUMBER='(F1)';
      PINUSE='GROUND';
      NO_LOAD_CHECK='Both';
      NO_IO_CHECK='Both';
      NO_ASSERT_CHECK='TRUE';
      NO_DIR_CHECK='TRUE';
      ALLOW_CONNECT='TRUE';
    'GNDF3':
      PIN_NUMBER='(F3)';
      PINUSE='GROUND';
      NO_LOAD_CHECK='Both';
      NO_IO_CHECK='Both';
      NO_ASSERT_CHECK='TRUE';
      NO_DIR_CHECK='TRUE';
      ALLOW_CONNECT='TRUE';
    'GNDF5':
      PIN_NUMBER='(F5)';
      PINUSE='GROUND';
      NO_LOAD_CHECK='Both';
      NO_IO_CHECK='Both';
      NO_ASSERT_CHECK='TRUE';
      NO_DIR_CHECK='TRUE';
      ALLOW_CONNECT='TRUE';
    'GNDF7':
      PIN_NUMBER='(F7)';
      PINUSE='GROUND';
      NO_LOAD_CHECK='Both';
      NO_IO_CHECK='Both';
      NO_ASSERT_CHECK='TRUE';
      NO_DIR_CHECK='TRUE';
      ALLOW_CONNECT='TRUE';
    'GNDG2':
      PIN_NUMBER='(G2)';
      PINUSE='GROUND';
      NO_LOAD_CHECK='Both';
      NO_IO_CHECK='Both';
      NO_ASSERT_CHECK='TRUE';
      NO_DIR_CHECK='TRUE';
      ALLOW_CONNECT='TRUE';
    'GNDG4':
      PIN_NUMBER='(G4)';
      PINUSE='GROUND';
      NO_LOAD_CHECK='Both';
      NO_IO_CHECK='Both';
      NO_ASSERT_CHECK='TRUE';
      NO_DIR_CHECK='TRUE';
      ALLOW_CONNECT='TRUE';
    'GNDG6':
      PIN_NUMBER='(G6)';
      PINUSE='GROUND';
      NO_LOAD_CHECK='Both';
      NO_IO_CHECK='Both';
      NO_ASSERT_CHECK='TRUE';
      NO_DIR_CHECK='TRUE';
      ALLOW_CONNECT='TRUE';
    'GNDG8':
      PIN_NUMBER='(G8)';
      PINUSE='GROUND';
      NO_LOAD_CHECK='Both';
      NO_IO_CHECK='Both';
      NO_ASSERT_CHECK='TRUE';
      NO_DIR_CHECK='TRUE';
      ALLOW_CONNECT='TRUE';
    'GNDI1':
      PIN_NUMBER='(I1)';
      PINUSE='GROUND';
      NO_LOAD_CHECK='Both';
      NO_IO_CHECK='Both';
      NO_ASSERT_CHECK='TRUE';
      NO_DIR_CHECK='TRUE';
      ALLOW_CONNECT='TRUE';
    'GNDI3':
      PIN_NUMBER='(I3)';
      PINUSE='GROUND';
      NO_LOAD_CHECK='Both';
      NO_IO_CHECK='Both';
      NO_ASSERT_CHECK='TRUE';
      NO_DIR_CHECK='TRUE';
      ALLOW_CONNECT='TRUE';
    'GNDI5':
      PIN_NUMBER='(I5)';
      PINUSE='GROUND';
      NO_LOAD_CHECK='Both';
      NO_IO_CHECK='Both';
      NO_ASSERT_CHECK='TRUE';
      NO_DIR_CHECK='TRUE';
      ALLOW_CONNECT='TRUE';
    'GNDI7':
      PIN_NUMBER='(I7)';
      PINUSE='GROUND';
      NO_LOAD_CHECK='Both';
      NO_IO_CHECK='Both';
      NO_ASSERT_CHECK='TRUE';
      NO_DIR_CHECK='TRUE';
      ALLOW_CONNECT='TRUE';
    'GNDJ2':
      PIN_NUMBER='(J2)';
      PINUSE='GROUND';
      NO_LOAD_CHECK='Both';
      NO_IO_CHECK='Both';
      NO_ASSERT_CHECK='TRUE';
      NO_DIR_CHECK='TRUE';
      ALLOW_CONNECT='TRUE';
    'GNDJ4':
      PIN_NUMBER='(J4)';
      PINUSE='GROUND';
      NO_LOAD_CHECK='Both';
      NO_IO_CHECK='Both';
      NO_ASSERT_CHECK='TRUE';
      NO_DIR_CHECK='TRUE';
      ALLOW_CONNECT='TRUE';
    'GNDJ6':
      PIN_NUMBER='(J6)';
      PINUSE='GROUND';
      NO_LOAD_CHECK='Both';
      NO_IO_CHECK='Both';
      NO_ASSERT_CHECK='TRUE';
      NO_DIR_CHECK='TRUE';
      ALLOW_CONNECT='TRUE';
    'GNDJ8':
      PIN_NUMBER='(J8)';
      PINUSE='GROUND';
      NO_LOAD_CHECK='Both';
      NO_IO_CHECK='Both';
      NO_ASSERT_CHECK='TRUE';
      NO_DIR_CHECK='TRUE';
      ALLOW_CONNECT='TRUE';
    'IOA1':
      PIN_NUMBER='(A1)';
      BIDIRECTIONAL='TRUE';
      INPUT_LOAD='(-0.01,0.01)';
      OUTPUT_LOAD='(1.0,-1.0)';
    'IOA3':
      PIN_NUMBER='(A3)';
      BIDIRECTIONAL='TRUE';
      INPUT_LOAD='(-0.01,0.01)';
      OUTPUT_LOAD='(1.0,-1.0)';
    'IOA5':
      PIN_NUMBER='(A5)';
      BIDIRECTIONAL='TRUE';
      INPUT_LOAD='(-0.01,0.01)';
      OUTPUT_LOAD='(1.0,-1.0)';
    'IOA7':
      PIN_NUMBER='(A7)';
      BIDIRECTIONAL='TRUE';
      INPUT_LOAD='(-0.01,0.01)';
      OUTPUT_LOAD='(1.0,-1.0)';
    'IOB1':
      PIN_NUMBER='(B1)';
      BIDIRECTIONAL='TRUE';
      INPUT_LOAD='(-0.01,0.01)';
      OUTPUT_LOAD='(1.0,-1.0)';
    'IOB2':
      PIN_NUMBER='(B2)';
      BIDIRECTIONAL='TRUE';
      INPUT_LOAD='(-0.01,0.01)';
      OUTPUT_LOAD='(1.0,-1.0)';
    'IOB3':
      PIN_NUMBER='(B3)';
      BIDIRECTIONAL='TRUE';
      INPUT_LOAD='(-0.01,0.01)';
      OUTPUT_LOAD='(1.0,-1.0)';
    'IOB4':
      PIN_NUMBER='(B4)';
      BIDIRECTIONAL='TRUE';
      INPUT_LOAD='(-0.01,0.01)';
      OUTPUT_LOAD='(1.0,-1.0)';
    'IOB5':
      PIN_NUMBER='(B5)';
      BIDIRECTIONAL='TRUE';
      INPUT_LOAD='(-0.01,0.01)';
      OUTPUT_LOAD='(1.0,-1.0)';
    'IOB6':
      PIN_NUMBER='(B6)';
      BIDIRECTIONAL='TRUE';
      INPUT_LOAD='(-0.01,0.01)';
      OUTPUT_LOAD='(1.0,-1.0)';
    'IOB7':
      PIN_NUMBER='(B7)';
      BIDIRECTIONAL='TRUE';
      INPUT_LOAD='(-0.01,0.01)';
      OUTPUT_LOAD='(1.0,-1.0)';
    'IOB8':
      PIN_NUMBER='(B8)';
      BIDIRECTIONAL='TRUE';
      INPUT_LOAD='(-0.01,0.01)';
      OUTPUT_LOAD='(1.0,-1.0)';
    'IOC2':
      PIN_NUMBER='(C2)';
      BIDIRECTIONAL='TRUE';
      INPUT_LOAD='(-0.01,0.01)';
      OUTPUT_LOAD='(1.0,-1.0)';
    'IOC4':
      PIN_NUMBER='(C4)';
      BIDIRECTIONAL='TRUE';
      INPUT_LOAD='(-0.01,0.01)';
      OUTPUT_LOAD='(1.0,-1.0)';
    'IOC6':
      PIN_NUMBER='(C6)';
      BIDIRECTIONAL='TRUE';
      INPUT_LOAD='(-0.01,0.01)';
      OUTPUT_LOAD='(1.0,-1.0)';
    'IOC8':
      PIN_NUMBER='(C8)';
      BIDIRECTIONAL='TRUE';
      INPUT_LOAD='(-0.01,0.01)';
      OUTPUT_LOAD='(1.0,-1.0)';
    'IOD1':
      PIN_NUMBER='(D1)';
      BIDIRECTIONAL='TRUE';
      INPUT_LOAD='(-0.01,0.01)';
      OUTPUT_LOAD='(1.0,-1.0)';
    'IOD3':
      PIN_NUMBER='(D3)';
      BIDIRECTIONAL='TRUE';
      INPUT_LOAD='(-0.01,0.01)';
      OUTPUT_LOAD='(1.0,-1.0)';
    'IOD5':
      PIN_NUMBER='(D5)';
      BIDIRECTIONAL='TRUE';
      INPUT_LOAD='(-0.01,0.01)';
      OUTPUT_LOAD='(1.0,-1.0)';
    'IOD7':
      PIN_NUMBER='(D7)';
      BIDIRECTIONAL='TRUE';
      INPUT_LOAD='(-0.01,0.01)';
      OUTPUT_LOAD='(1.0,-1.0)';
    'IOE1':
      PIN_NUMBER='(E1)';
      BIDIRECTIONAL='TRUE';
      INPUT_LOAD='(-0.01,0.01)';
      OUTPUT_LOAD='(1.0,-1.0)';
    'IOE2':
      PIN_NUMBER='(E2)';
      BIDIRECTIONAL='TRUE';
      INPUT_LOAD='(-0.01,0.01)';
      OUTPUT_LOAD='(1.0,-1.0)';
    'IOE3':
      PIN_NUMBER='(E3)';
      BIDIRECTIONAL='TRUE';
      INPUT_LOAD='(-0.01,0.01)';
      OUTPUT_LOAD='(1.0,-1.0)';
    'IOE4':
      PIN_NUMBER='(E4)';
      BIDIRECTIONAL='TRUE';
      INPUT_LOAD='(-0.01,0.01)';
      OUTPUT_LOAD='(1.0,-1.0)';
    'IOE5':
      PIN_NUMBER='(E5)';
      BIDIRECTIONAL='TRUE';
      INPUT_LOAD='(-0.01,0.01)';
      OUTPUT_LOAD='(1.0,-1.0)';
    'IOE6':
      PIN_NUMBER='(E6)';
      BIDIRECTIONAL='TRUE';
      INPUT_LOAD='(-0.01,0.01)';
      OUTPUT_LOAD='(1.0,-1.0)';
    'IOE7':
      PIN_NUMBER='(E7)';
      BIDIRECTIONAL='TRUE';
      INPUT_LOAD='(-0.01,0.01)';
      OUTPUT_LOAD='(1.0,-1.0)';
    'IOE8':
      PIN_NUMBER='(E8)';
      BIDIRECTIONAL='TRUE';
      INPUT_LOAD='(-0.01,0.01)';
      OUTPUT_LOAD='(1.0,-1.0)';
    'IOF2':
      PIN_NUMBER='(F2)';
      BIDIRECTIONAL='TRUE';
      INPUT_LOAD='(-0.01,0.01)';
      OUTPUT_LOAD='(1.0,-1.0)';
    'IOF4':
      PIN_NUMBER='(F4)';
      BIDIRECTIONAL='TRUE';
      INPUT_LOAD='(-0.01,0.01)';
      OUTPUT_LOAD='(1.0,-1.0)';
    'IOF6':
      PIN_NUMBER='(F6)';
      BIDIRECTIONAL='TRUE';
      INPUT_LOAD='(-0.01,0.01)';
      OUTPUT_LOAD='(1.0,-1.0)';
    'IOF8':
      PIN_NUMBER='(F8)';
      BIDIRECTIONAL='TRUE';
      INPUT_LOAD='(-0.01,0.01)';
      OUTPUT_LOAD='(1.0,-1.0)';
    'IOG1':
      PIN_NUMBER='(G1)';
      BIDIRECTIONAL='TRUE';
      INPUT_LOAD='(-0.01,0.01)';
      OUTPUT_LOAD='(1.0,-1.0)';
    'IOG3':
      PIN_NUMBER='(G3)';
      BIDIRECTIONAL='TRUE';
      INPUT_LOAD='(-0.01,0.01)';
      OUTPUT_LOAD='(1.0,-1.0)';
    'IOG5':
      PIN_NUMBER='(G5)';
      BIDIRECTIONAL='TRUE';
      INPUT_LOAD='(-0.01,0.01)';
      OUTPUT_LOAD='(1.0,-1.0)';
    'IOG7':
      PIN_NUMBER='(G7)';
      BIDIRECTIONAL='TRUE';
      INPUT_LOAD='(-0.01,0.01)';
      OUTPUT_LOAD='(1.0,-1.0)';
    'IOH1':
      PIN_NUMBER='(H1)';
      BIDIRECTIONAL='TRUE';
      INPUT_LOAD='(-0.01,0.01)';
      OUTPUT_LOAD='(1.0,-1.0)';
    'IOH2':
      PIN_NUMBER='(H2)';
      BIDIRECTIONAL='TRUE';
      INPUT_LOAD='(-0.01,0.01)';
      OUTPUT_LOAD='(1.0,-1.0)';
    'IOH3':
      PIN_NUMBER='(H3)';
      BIDIRECTIONAL='TRUE';
      INPUT_LOAD='(-0.01,0.01)';
      OUTPUT_LOAD='(1.0,-1.0)';
    'IOH4':
      PIN_NUMBER='(H4)';
      BIDIRECTIONAL='TRUE';
      INPUT_LOAD='(-0.01,0.01)';
      OUTPUT_LOAD='(1.0,-1.0)';
    'IOH5':
      PIN_NUMBER='(H5)';
      BIDIRECTIONAL='TRUE';
      INPUT_LOAD='(-0.01,0.01)';
      OUTPUT_LOAD='(1.0,-1.0)';
    'IOH6':
      PIN_NUMBER='(H6)';
      BIDIRECTIONAL='TRUE';
      INPUT_LOAD='(-0.01,0.01)';
      OUTPUT_LOAD='(1.0,-1.0)';
    'IOH7':
      PIN_NUMBER='(H7)';
      BIDIRECTIONAL='TRUE';
      INPUT_LOAD='(-0.01,0.01)';
      OUTPUT_LOAD='(1.0,-1.0)';
    'IOH8':
      PIN_NUMBER='(H8)';
      BIDIRECTIONAL='TRUE';
      INPUT_LOAD='(-0.01,0.01)';
      OUTPUT_LOAD='(1.0,-1.0)';
    'IOI2':
      PIN_NUMBER='(I2)';
      BIDIRECTIONAL='TRUE';
      INPUT_LOAD='(-0.01,0.01)';
      OUTPUT_LOAD='(1.0,-1.0)';
    'IOI4':
      PIN_NUMBER='(I4)';
      BIDIRECTIONAL='TRUE';
      INPUT_LOAD='(-0.01,0.01)';
      OUTPUT_LOAD='(1.0,-1.0)';
    'IOI6':
      PIN_NUMBER='(I6)';
      BIDIRECTIONAL='TRUE';
      INPUT_LOAD='(-0.01,0.01)';
      OUTPUT_LOAD='(1.0,-1.0)';
    'IOI8':
      PIN_NUMBER='(I8)';
      BIDIRECTIONAL='TRUE';
      INPUT_LOAD='(-0.01,0.01)';
      OUTPUT_LOAD='(1.0,-1.0)';
  end_pin;
  body
    PART_NAME='CONN76_H22707001';
    PHYS_DES_PREFIX='J';
  end_body;
end_primitive;

END.
